# TIMECARD (Time Appliance Project (Time Card)) — schematic netlist excerpt (pin names and nets, part order shuffled) for the footprints in the layout excerpt that follows; sources: Cadence DE-HDL packaged netlist, KiCad conversion of R4006-B0001-02_R01.brd

R353  RESISTOR  100OHM 1%  pkg SMC_0402R_H016  page 24 : \1\ = R_FT4232_CHC_TX ; \2\ = UART_FT4232_TX_FPGA_RX
C308  CAPACITOR  10UF 25V 20%  pkg SMC_0805R_H057  page 33 : \1\ = XP3R3V_FT4232 ; \2\ = SG

(kicad_pcb
	(version 20260206)
	(generator "pcbnew")
	(generator_version "10.0")
	(general
		(thickness 1.6)
		(legacy_teardrops no)
	)
	(paper "A4")
	(title_block
		(title "timecard-production-celestica-r4006 — R4006-B0001-02_R01.brd")
		(comment 1 "Time Appliance Project (Time Card) / footprints 647-648 of 1113")
	)
	(layers
		(0 "F.Cu" signal "TOP")
		(4 "In1.Cu" signal "L02_GND1")
		(6 "In2.Cu" signal "L03_SIG1")
		(8 "In3.Cu" signal "L04_GND2")
		(10 "In4.Cu" signal "L05_VCC1")
		(12 "In5.Cu" signal "L06_VCC2")
		(14 "In6.Cu" signal "L07_GND3")
		(16 "In7.Cu" signal "L08_SIG2")
		(18 "In8.Cu" signal "L09_GND4")
		(2 "B.Cu" signal "BOTTOM")
		(9 "F.Adhes" user "F.Adhesive")
		(11 "B.Adhes" user "B.Adhesive")
		(13 "F.Paste" user "Package Geometry/Pastemask Top")
		(15 "B.Paste" user "Package Geometry/Pastemask Bottom")
		(5 "F.SilkS" user "Ref Des/Silkscreen Top")
		(7 "B.SilkS" user "Ref Des/Silkscreen Bottom")
		(1 "F.Mask" user "Board Geometry/Soldermask Top")
		(3 "B.Mask" user "Board Geometry/Soldermask Bottom")
		(17 "Dwgs.User" user "User.Drawings")
		(19 "Cmts.User" user "User.Comments")
		(21 "Eco1.User" user "User.Eco1")
		(23 "Eco2.User" user "User.Eco2")
		(25 "Edge.Cuts" user "Board Geometry/Outline")
		(27 "Margin" user)
		(31 "F.CrtYd" user "Package Geometry/Place Bound Top")
		(29 "B.CrtYd" user "Package Geometry/Place Bound Bottom")
		(35 "F.Fab" user "Ref Des/Assembly Top")
		(33 "B.Fab" user "Ref Des/Assembly Bottom")
	)
	(footprint ""
		(layer "F.Cu")
		(at 27.305 -75.184 -90)
		(property "Reference" "R353"
			(at 3.175 -0.29337 90)
			(unlocked yes)
			(layer "F.SilkS")
			(effects
				(font
					(size 0.7874 0.5842)
					(thickness 0.1524)
				)
			)
		)
		(property "Value" "VAL*"
			(at 0.02032 2.13233 270)
			(unlocked yes)
			(layer "F.Fab")
			(hide yes)
			(effects
				(font
					(size 0.7874 0.5842)
					(thickness 0.1524)
				)
			)
		)
		(property "Tolerance" "TOL*"
			(at 0.044704 3.05435 270)
			(unlocked yes)
			(layer "Cmts.User")
			(hide yes)
			(effects
				(font
					(size 0.7874 0.5842)
					(thickness 0.1524)
				)
			)
		)
		(property "User Part Number" "PARTNUM*"
			(at 0.02032 4.024884 270)
			(unlocked yes)
			(layer "Cmts.User")
			(hide yes)
			(effects
				(font
					(size 0.7874 0.5842)
					(thickness 0.1524)
				)
			)
		)
		(property "Device Type" "RESISTOR-G155-11000-01,100OHM,A"
			(at 0.008382 1.210564 270)
			(unlocked yes)
			(layer "F.Fab")
			(hide yes)
			(effects
				(font
					(size 0.7874 0.5842)
					(thickness 0.1524)
				)
			)
		)
		(duplicate_pad_numbers_are_jumpers no)
		(fp_line
			(start -1.143 0.5588)
			(end 1.143 0.5588)
			(stroke
				(width 0.1)
				(type default)
			)
			(layer "F.SilkS")
		)
		(fp_line
			(start 1.143 0.5588)
			(end 1.143 -0.5588)
			(stroke
				(width 0.1)
				(type default)
			)
			(layer "F.SilkS")
		)
		(fp_line
			(start -1.143 -0.5588)
			(end -1.143 0.5588)
			(stroke
				(width 0.1)
				(type default)
			)
			(layer "F.SilkS")
		)
		(fp_line
			(start 1.143 -0.5588)
			(end -1.143 -0.5588)
			(stroke
				(width 0.1)
				(type default)
			)
			(layer "F.SilkS")
		)
		(fp_poly
			(pts
				(xy -1.143 0.5588) (xy 1.143 0.5588) (xy 1.143 -0.5588) (xy -1.143 -0.5588)
			)
			(stroke
				(width 0)
				(type default)
			)
			(fill no)
			(layer "F.CrtYd")
		)
		(fp_line
			(start -0.508 0.3048)
			(end 0.508 0.3048)
			(stroke
				(width 0.1)
				(type default)
			)
			(layer "F.Fab")
		)
		(fp_line
			(start 0.508 0.3048)
			(end 0.508 -0.3048)
			(stroke
				(width 0.1)
				(type default)
			)
			(layer "F.Fab")
		)
		(fp_line
			(start -0.508 -0.3048)
			(end -0.508 0.3048)
			(stroke
				(width 0.1)
				(type default)
			)
			(layer "F.Fab")
		)
		(fp_line
			(start 0.508 -0.3048)
			(end -0.508 -0.3048)
			(stroke
				(width 0.1)
				(type default)
			)
			(layer "F.Fab")
		)
		(pad "1" smd rect
			(at -0.5334 0 270)
			(size 0.7112 0.6096)
			(layers "F.Cu" "F.Mask" "F.Paste")
			(net "R_FT4232_CHC_TX")
		)
		(pad "2" smd rect
			(at 0.5334 0 270)
			(size 0.7112 0.6096)
			(layers "F.Cu" "F.Mask" "F.Paste")
			(net "UART_FT4232_TX_FPGA_RX")
		)
		(zone
			(layer "F.Cu")
			(hatch none 0.5)
			(connect_pads
				(clearance 0)
			)
			(min_thickness 0.25)
			(keepout
				(tracks not_allowed)
				(vias allowed)
				(pads allowed)
				(copperpour not_allowed)
				(footprints allowed)
			)
			(placement
				(enabled no)
				(sheetname "")
			)
			(fill
				(thermal_gap 0.5)
				(thermal_bridge_width 0.5)
				(island_removal_mode 0)
			)
			(polygon
				(pts
					(xy 27.0002 -75.2602) (xy 27.0002 -75.1078) (xy 27.6098 -75.1078) (xy 27.6098 -75.2602)
				)
			)
		)
		(zone
			(layer "F.Cu")
			(hatch none 0.5)
			(connect_pads
				(clearance 0)
			)
			(min_thickness 0.25)
			(keepout
				(tracks allowed)
				(vias not_allowed)
				(pads allowed)
				(copperpour not_allowed)
				(footprints allowed)
			)
			(placement
				(enabled no)
				(sheetname "")
			)
			(fill
				(thermal_gap 0.5)
				(thermal_bridge_width 0.5)
				(island_removal_mode 0)
			)
			(polygon
				(pts
					(xy 27.0002 -75.2602) (xy 27.0002 -75.1078) (xy 27.6098 -75.1078) (xy 27.6098 -75.2602)
				)
			)
		)
	)
	(footprint ""
		(layer "F.Cu")
		(at 37.084 -77.216 -90)
		(property "Reference" "C308"
			(at 1.27 3.00863 90)
			(unlocked yes)
			(layer "F.SilkS")
			(effects
				(font
					(size 0.7874 0.5842)
					(thickness 0.1524)
				)
			)
		)
		(property "Value" "VAL*"
			(at 0.0762 3.134106 270)
			(unlocked yes)
			(layer "F.Fab")
			(hide yes)
			(effects
				(font
					(size 0.7874 0.5842)
					(thickness 0.1524)
				)
			)
		)
		(property "Tolerance" "TOL*"
			(at 0.0762 4.048506 270)
			(unlocked yes)
			(layer "Cmts.User")
			(hide yes)
			(effects
				(font
					(size 0.7874 0.5842)
					(thickness 0.1524)
				)
			)
		)
		(property "User Part Number" "PARTNUM*"
			(at 0.1016 5.013706 270)
			(unlocked yes)
			(layer "Cmts.User")
			(hide yes)
			(effects
				(font
					(size 0.7874 0.5842)
					(thickness 0.1524)
				)
			)
		)
		(property "Device Type" "CAPACITOR-G107-0F106-EM,10UF,2A"
			(at 0.0508 2.194306 270)
			(unlocked yes)
			(layer "F.Fab")
			(hide yes)
			(effects
				(font
					(size 0.7874 0.5842)
					(thickness 0.1524)
				)
			)
		)
		(duplicate_pad_numbers_are_jumpers no)
		(fp_line
			(start -1.5748 0.9398)
			(end 1.5748 0.9398)
			(stroke
				(width 0.1)
				(type default)
			)
			(layer "F.SilkS")
		)
		(fp_line
			(start 1.5748 0.9398)
			(end 1.5748 -0.9398)
			(stroke
				(width 0.1)
				(type default)
			)
			(layer "F.SilkS")
		)
		(fp_line
			(start -1.5748 -0.9398)
			(end -1.5748 0.9398)
			(stroke
				(width 0.1)
				(type default)
			)
			(layer "F.SilkS")
		)
		(fp_line
			(start 1.5748 -0.9398)
			(end -1.5748 -0.9398)
			(stroke
				(width 0.1)
				(type default)
			)
			(layer "F.SilkS")
		)
		(fp_poly
			(pts
				(xy -1.5748 0.9398) (xy 1.5748 0.9398) (xy 1.5748 -0.9398) (xy -1.5748 -0.9398)
			)
			(stroke
				(width 0)
				(type default)
			)
			(fill no)
			(layer "F.CrtYd")
		)
		(fp_line
			(start -1.016 0.635)
			(end 1.016 0.635)
			(stroke
				(width 0.1)
				(type default)
			)
			(layer "F.Fab")
		)
		(fp_line
			(start 1.016 0.635)
			(end 1.016 -0.635)
			(stroke
				(width 0.1)
				(type default)
			)
			(layer "F.Fab")
		)
		(fp_line
			(start -1.016 -0.635)
			(end -1.016 0.635)
			(stroke
				(width 0.1)
				(type default)
			)
			(layer "F.Fab")
		)
		(fp_line
			(start 1.016 -0.635)
			(end -1.016 -0.635)
			(stroke
				(width 0.1)
				(type default)
			)
			(layer "F.Fab")
		)
		(pad "1" smd rect
			(at -0.8382 0 270)
			(size 0.9652 1.3716)
			(layers "F.Cu" "F.Mask" "F.Paste")
			(net "XP3R3V_FT4232")
		)
		(pad "2" smd rect
			(at 0.8382 0 270)
			(size 0.9652 1.3716)
			(layers "F.Cu" "F.Mask" "F.Paste")
			(net "SG")
		)
		(zone
			(layer "F.Cu")
			(hatch none 0.5)
			(connect_pads
				(clearance 0)
			)
			(min_thickness 0.25)
			(keepout
				(tracks allowed)
				(vias not_allowed)
				(pads allowed)
				(copperpour not_allowed)
				(footprints allowed)
			)
			(placement
				(enabled no)
				(sheetname "")
			)
			(fill
				(thermal_gap 0.5)
				(thermal_bridge_width 0.5)
				(island_removal_mode 0)
			)
			(polygon
				(pts
					(xy 36.449 -77.4446) (xy 36.449 -76.9874) (xy 37.719 -76.9874) (xy 37.719 -77.4446)
				)
			)
		)
		(zone
			(layer "F.Cu")
			(hatch none 0.5)
			(connect_pads
				(clearance 0)
			)
			(min_thickness 0.25)
			(keepout
				(tracks not_allowed)
				(vias allowed)
				(pads allowed)
				(copperpour not_allowed)
				(footprints allowed)
			)
			(placement
				(enabled no)
				(sheetname "")
			)
			(fill
				(thermal_gap 0.5)
				(thermal_bridge_width 0.5)
				(island_removal_mode 0)
			)
			(polygon
				(pts
					(xy 36.449 -77.4446) (xy 36.449 -76.9874) (xy 37.719 -76.9874) (xy 37.719 -77.4446)
				)
			)
		)
	)
)
